FILE_TYPE=LIBRARY_PARTS;
TIME=' Created/Modified on Fri Feb 08 08:35:19 2002' ;
primitive 'CAP','CAP_0402';
  pin
    'A':
      PIN_NUMBER='(1)';
      PINUSE='UNSPEC';
      NO_LOAD_CHECK='BOTH';
      NO_IO_CHECK='BOTH';
      ALLOW_CONNECT='TRUE';
      PIN_GROUP='1';
    'B':
      PIN_NUMBER='(2)';
      PINUSE='UNSPEC';
      NO_LOAD_CHECK='BOTH';
      NO_IO_CHECK='BOTH';
      ALLOW_CONNECT='TRUE';
      PIN_GROUP='1';
  end_pin;
  body
    PART_NAME='CAP';
    PHYS_DES_PREFIX='C';
  end_body;
end_primitive;
END.
